#ISCELL
  logical_power design_note *
  *
#ISCELL
  mstr_misc dns *
  *
#ISCELL
  pure_quanta quanta_title_block_c *
  *
#ISCELL
  standard offpage *
  page175_i101
#CELL
  pure_quanta q_res *
  page175_i102
#CELL
  pure_quanta q_res *
  page175_i109
#ISCELL
  standard offpage *
  page175_i110
#ISCELL
  logical_power universal_power *
  page175_i111
#CELL
  pure_quanta q_res *
  page175_i112
#ISCELL
  standard offpage *
  page175_i113
#ISCELL
  standard offpage *
  page175_i118
#ISCELL
  standard offpage *
  page175_i119
#CELL
  pure_quanta q_res *
  page175_i120
#CELL
  pure_quanta q_res *
  page175_i121
#CELL
  pure_quanta q_res *
  page175_i125
#ISCELL
  logical_power universal_gnd *
  page175_i126
#ISCELL
  standard offpage *
  page175_i131
#ISCELL
  standard offpage *
  page175_i132
#ISCELL
  standard offpage *
  page175_i134
#ISCELL
  standard offpage *
  page175_i135
#ISCELL
  standard offpage *
  page175_i136
#CELL
  pure_quanta q_res *
  page175_i137
#CELL
  pure_quanta q_res *
  page175_i138
#ISCELL
  standard offpage *
  page175_i139
#ISCELL
  standard offpage *
  page175_i140
#CELL
  pure_quanta q_res *
  page175_i141
#CELL
  pure_quanta q_res *
  page175_i142
#ISCELL
  standard offpage *
  page175_i143
#CELL
  pure_quanta q_res *
  page175_i144
#ISCELL
  standard offpage *
  page175_i145
#ISCELL
  standard offpage *
  page175_i147
#CELL
  pure_quanta q_res *
  page175_i148
#ISCELL
  standard offpage *
  page175_i15
#ISCELL
  standard offpage *
  page175_i150
#CELL
  pure_quanta q_res *
  page175_i151
#ISCELL
  standard offpage *
  page175_i16
#ISCELL
  standard offpage *
  page175_i17
#ISCELL
  standard offpage *
  page175_i175
#ISCELL
  standard offpage *
  page175_i177
#CELL
  pure_quanta q_res *
  page175_i178
#ISCELL
  standard offpage *
  page175_i18
#CELL
  pure_quanta q_res *
  page175_i180
#CELL
  pure_quanta q_res *
  page175_i181
#ISCELL
  standard offpage *
  page175_i182
#ISCELL
  standard offpage *
  page175_i183
#CELL
  pure_quanta q_res *
  page175_i188
#ISCELL
  standard offpage *
  page175_i189
#ISCELL
  standard offpage *
  page175_i19
#CELL
  pure_quanta q_res *
  page175_i193
#ISCELL
  standard offpage *
  page175_i194
#ISCELL
  standard offpage *
  page175_i195
#ISCELL
  standard offpage *
  page175_i20
#ISCELL
  standard offpage *
  page175_i209
#ISCELL
  standard offpage *
  page175_i21
#ISCELL
  standard offpage *
  page175_i210
#ISCELL
  standard offpage *
  page175_i212
#CELL
  pure_quanta q_res *
  page175_i213
#ISCELL
  standard offpage *
  page175_i22
#CELL
  pure_quanta q_res *
  page175_i222
#ISCELL
  standard offpage *
  page175_i223
#ISCELL
  logical_power universal_gnd *
  page175_i224
#CELL
  pure_quanta q_res *
  page175_i225
#ISCELL
  standard offpage *
  page175_i227
#ISCELL
  standard offpage *
  page175_i228
#ISCELL
  standard offpage *
  page175_i229
#ISCELL
  standard offpage *
  page175_i23
#ISCELL
  standard offpage *
  page175_i230
#CELL
  pure_quanta q_res *
  page175_i234
#ISCELL
  standard offpage *
  page175_i235
#CELL
  pure_quanta q_res *
  page175_i236
#ISCELL
  standard offpage *
  page175_i237
#ISCELL
  standard offpage *
  page175_i238
#CELL
  pure_quanta q_res *
  page175_i239
#ISCELL
  standard offpage *
  page175_i24
#ISCELL
  standard offpage *
  page175_i240
#CELL
  pure_quanta q_res *
  page175_i241
#ISCELL
  standard offpage *
  page175_i246
#ISCELL
  standard offpage *
  page175_i247
#ISCELL
  standard offpage *
  page175_i248
#ISCELL
  standard offpage *
  page175_i249
#ISCELL
  standard offpage *
  page175_i25
#ISCELL
  standard offpage *
  page175_i250
#ISCELL
  standard offpage *
  page175_i252
#CELL
  pure_quanta q_res *
  page175_i253
#CELL
  pure_quanta conn3_210hp1030br1 *
  page175_i256
#ISCELL
  logical_power universal_gnd *
  page175_i257
#ISCELL
  standard offpage *
  page175_i258
#ISCELL
  standard offpage *
  page175_i259
#ISCELL
  standard offpage *
  page175_i26
#ISCELL
  logical_power universal_gnd *
  page175_i260
#ISCELL
  standard offpage *
  page175_i261
#ISCELL
  standard offpage *
  page175_i262
#CELL
  pure_quanta conn3_210hp1030br1 *
  page175_i263
#ISCELL
  standard offpage *
  page175_i268
#ISCELL
  standard offpage *
  page175_i269
#ISCELL
  standard offpage *
  page175_i27
#ISCELL
  standard offpage *
  page175_i271
#CELL
  pure_quanta q_res *
  page175_i272
#ISCELL
  standard offpage *
  page175_i273
#CELL
  pure_quanta q_res *
  page175_i274
#CELL
  pure_quanta q_res *
  page175_i275
#ISCELL
  standard offpage *
  page175_i276
#ISCELL
  standard offpage *
  page175_i277
#ISCELL
  standard offpage *
  page175_i278
#ISCELL
  standard offpage *
  page175_i279
#ISCELL
  standard offpage *
  page175_i28
#ISCELL
  standard offpage *
  page175_i280
#ISCELL
  standard offpage *
  page175_i281
#ISCELL
  standard offpage *
  page175_i282
#CELL
  pure_quanta q_res *
  page175_i284
#CELL
  pure_quanta q_res *
  page175_i285
#CELL
  pure_quanta q_res *
  page175_i286
#CELL
  pure_quanta q_res *
  page175_i287
#CELL
  pure_quanta q_res *
  page175_i288
#ISCELL
  logical_power universal_gnd *
  page175_i289
#ISCELL
  standard offpage *
  page175_i29
#ISCELL
  standard offpage *
  page175_i290
#ISCELL
  standard offpage *
  page175_i291
#ISCELL
  standard offpage *
  page175_i292
#ISCELL
  standard offpage *
  page175_i293
#ISCELL
  standard offpage *
  page175_i294
#ISCELL
  standard offpage *
  page175_i295
#ISCELL
  standard offpage *
  page175_i296
#ISCELL
  standard offpage *
  page175_i297
#CELL
  pure_quanta q_res *
  page175_i298
#CELL
  pure_quanta q_res *
  page175_i299
#ISCELL
  standard offpage *
  page175_i30
#CELL
  pure_quanta q_res *
  page175_i300
#ISCELL
  standard offpage *
  page175_i302
#ISCELL
  standard offpage *
  page175_i303
#ISCELL
  standard offpage *
  page175_i304
#CELL
  pure_quanta q_res *
  page175_i305
#ISCELL
  standard offpage *
  page175_i306
#ISCELL
  standard offpage *
  page175_i307
#CELL
  pure_quanta q_res *
  page175_i308
#ISCELL
  standard offpage *
  page175_i309
#ISCELL
  standard offpage *
  page175_i31
#ISCELL
  standard offpage *
  page175_i310
#ISCELL
  standard offpage *
  page175_i311
#ISCELL
  standard offpage *
  page175_i312
#CELL
  pure_quanta q_res *
  page175_i314
#CELL
  pure_quanta q_res *
  page175_i315
#ISCELL
  standard offpage *
  page175_i317
#ISCELL
  standard offpage *
  page175_i32
#ISCELL
  standard offpage *
  page175_i33
#ISCELL
  standard offpage *
  page175_i36
#ISCELL
  standard offpage *
  page175_i37
#ISCELL
  standard offpage *
  page175_i38
#ISCELL
  standard offpage *
  page175_i39
#ISCELL
  standard offpage *
  page175_i40
#ISCELL
  standard offpage *
  page175_i41
#ISCELL
  standard offpage *
  page175_i42
#ISCELL
  standard offpage *
  page175_i43
#ISCELL
  standard offpage *
  page175_i44
#ISCELL
  standard offpage *
  page175_i45
#ISCELL
  standard offpage *
  page175_i46
#ISCELL
  standard offpage *
  page175_i49
#ISCELL
  standard offpage *
  page175_i50
#ISCELL
  standard offpage *
  page175_i51
#ISCELL
  standard offpage *
  page175_i53
#ISCELL
  standard offpage *
  page175_i56
#ISCELL
  standard offpage *
  page175_i57
#ISCELL
  standard offpage *
  page175_i58
#ISCELL
  standard offpage *
  page175_i60
#ISCELL
  standard offpage *
  page175_i62
#ISCELL
  standard offpage *
  page175_i67
#ISCELL
  standard offpage *
  page175_i68
#ISCELL
  standard offpage *
  page175_i70
#ISCELL
  standard offpage *
  page175_i71
#ISCELL
  standard offpage *
  page175_i72
#ISCELL
  standard offpage *
  page175_i73
#ISCELL
  standard offpage *
  page175_i74
#ISCELL
  standard offpage *
  page175_i75
#ISCELL
  standard offpage *
  page175_i76
#ISCELL
  standard offpage *
  page175_i77
#ISCELL
  standard offpage *
  page175_i78
#ISCELL
  standard offpage *
  page175_i79
#ISCELL
  standard offpage *
  page175_i80
#ISCELL
  standard offpage *
  page175_i81
#ISCELL
  standard offpage *
  page175_i83
#ISCELL
  standard offpage *
  page175_i85
#ISCELL
  standard offpage *
  page175_i86
#ISCELL
  standard offpage *
  page175_i87
#ISCELL
  standard offpage *
  page175_i88
#ISCELL
  standard offpage *
  page175_i89
#ISCELL
  standard offpage *
  page175_i90
#ISCELL
  standard offpage *
  page175_i91
#ISCELL
  standard offpage *
  page175_i92
#CELL
  pure_quanta emmitsburg_rev0p9 *
  page175_i93
#ISCELL
  standard offpage *
  page175_i99
